FILE_TYPE = MACRO_DRAWING;
SET COLOR_WIRE YELLOW;
SET COLOR_PROP ORANGE;
SET COLOR_DOT WHITE;
SET COLOR_ARC YELLOW;
SET COLOR_BODY GREEN;
SET COLOR_NOTE PURPLE;
SET PROP_DISPLAY VALUE;
SET PAGE_NUMBER P521;
FORCEADD SHEET_A1..1
(700 50);
FORCEPROP 2 LAST CUSTOM_TXT_CDS <XR_PAGE_TITLE>
J 0
(-14870 11400);
DISPLAY 0.638298 (-14870 11400);
PAINT PINK (-14870 11400);
FORCEPROP 1 LAST CUSTOM_TXT_CDS <DOCNO>
J 0
(-1350 435);
DISPLAY 0.978723 (-1350 435);
FORCEPROP 1 LAST CUSTOM_TXT_CDS <CON_PAGE_NUM>
J 0
(-1455 100);
DISPLAY 0.978723 (-1455 100);
FORCEPROP 1 LAST CUSTOM_TXT_CDS <DATE>
J 0
(0 225);
DISPLAY 0.978723 (0 225);
FORCEPROP 1 LAST CUSTOM_TXT_CDS <TITLE>
J 1
(-1085 680);
DISPLAY 0.978723 (-1085 680);
FORCEPROP 1 LAST CUSTOM_TXT_CDS <DESIGNER>
J 0
(0 650);
DISPLAY 0.978723 (0 650);
FORCEPROP 1 LAST CUSTOM_TXT_CDS <CON_TOTAL_PAGES>
J 0
(-1145 100);
DISPLAY 0.808511 (-1145 100);
FORCEPROP 1 LAST CUSTOM_TXT_CDS <ASSY_PN>
J 0
(-1350 225);
DISPLAY 0.978723 (-1350 225);
FORCEPROP 1 LAST CUSTOM_TXT_CDS <DOCREV>
J 0
(0 425);
DISPLAY 0.978723 (0 425);
FORCEPROP 1 LAST TITLE PWR_BLOCK_DIAGRAM
J 0
(-1800 900);
DISPLAY 3.042553 (-1800 900);
PAINT GREEN (-1800 900);
FORCEPROP 1 LAST COMMENT_BODY TRUE
J 0
(710 105);
DISPLAY 0.808511 (710 105);
DISPLAY INVISIBLE (710 105);
FORCEPROP 2 LAST PAGE_BORDER TRUE
J 0
(-14870 11400);
DISPLAY 0.638298 (-14870 11400);
PAINT PINK (-14870 11400);
DISPLAY INVISIBLE (-14870 11400);
FORCEPROP 1 LAST CDS_LMAN_SYM_OUTLINE -15850,11500,200,-200
J 0
(700 50);
DISPLAY 0.468085 (700 50);
PAINT GREEN (700 50);
DISPLAY INVISIBLE (700 50);
FORCEPROP 2 LAST CDS_LIB cls
J 0
(700 50);
DISPLAY INVISIBLE (700 50);
FORCEPROP 2 LAST CDS_XR_PAGE_TITLE CR-6 : @TIMECARD_LIB.TIMECARD(SCH_1):PAGE6
J 0
(-14870 11400);
DISPLAY 0.638298 (-14870 11400);
PAINT PINK (-14870 11400);
DISPLAY INVISIBLE (-14870 11400);
FORCENOTE
PWR_BLOCK_DIAGRAM
(-8950 10250) 0;
DISPLAY LEFT (-8950 10250);
DISPLAY 4.914894 (-8950 10250);
FORCENOTE
$CDS_IMAGE|clipboard_0_10.jpg|7118|5333
(-6850 6200) 0;
DISPLAY LEFT (-6850 6200);
QUIT
